(kicad_pcb
	(version 20260206)
	(generator "pcbnew")
	(generator_version "10.0")
	(general
		(thickness 1.6)
		(legacy_teardrops no)
	)
	(paper "A4")
	(title_block
		(title "Bryce Canyon_IOM_IOC_16318-2_OCP.brd")
		(comment 1 "Bryce Canyon / footprints 1568-1576 of 1605")
	)
	(layers
		(0 "F.Cu" signal "TOP")
		(4 "In1.Cu" signal "L2GND")
		(6 "In2.Cu" signal "L3")
		(8 "In3.Cu" signal "L4VCC")
		(10 "In4.Cu" signal "L5VCC")
		(12 "In5.Cu" signal "L6")
		(14 "In6.Cu" signal "L7GND")
		(2 "B.Cu" signal "BOTTOM")
		(9 "F.Adhes" user "F.Adhesive")
		(11 "B.Adhes" user "B.Adhesive")
		(13 "F.Paste" user "Package Geometry/Pastemask Top")
		(15 "B.Paste" user "Package Geometry/Pastemask Bottom")
		(5 "F.SilkS" user "Ref Des/Silkscreen Top")
		(7 "B.SilkS" user "Ref Des/Silkscreen Bottom")
		(1 "F.Mask" user "Board Geometry/Soldermask Top")
		(3 "B.Mask" user "Board Geometry/Soldermask Bottom")
		(17 "Dwgs.User" user "User.Drawings")
		(19 "Cmts.User" user "User.Comments")
		(21 "Eco1.User" user "User.Eco1")
		(23 "Eco2.User" user "User.Eco2")
		(25 "Edge.Cuts" user "Board Geometry/Outline")
		(27 "Margin" user)
		(31 "F.CrtYd" user "Package Geometry/Place Bound Top")
		(29 "B.CrtYd" user "Package Geometry/Place Bound Bottom")
		(35 "F.Fab" user "Ref Des/Assembly Top")
		(33 "B.Fab" user "Ref Des/Assembly Bottom")
	)
	(footprint ""
		(layer "B.Cu")
		(at 203.8731 -54.94782)
		(property "Reference" "C453"
			(at 0 0 0)
			(layer "B.SilkS")
			(hide yes)
			(effects
				(font
					(size 1.27 1.27)
				)
				(justify mirror)
			)
		)
		(property "Value" "SCD1U16V2KX-3GP"
			(at -1.1811 -2.7051 0)
			(unlocked yes)
			(layer "B.Fab")
			(hide yes)
			(effects
				(font
					(size 1.016 1.016)
					(thickness 0.1524)
				)
				(justify mirror)
			)
		)
		(property "Device Type" "C402H22"
			(at -1.1811 -4.2291 0)
			(unlocked yes)
			(layer "B.Fab")
			(hide yes)
			(effects
				(font
					(size 1.016 1.016)
					(thickness 0.1524)
				)
				(justify mirror)
			)
		)
		(duplicate_pad_numbers_are_jumpers no)
		(fp_rect
			(start 0.4318 0.9525)
			(end -0.4318 -0.9525)
			(stroke
				(width 0)
				(type default)
			)
			(fill no)
			(layer "B.CrtYd")
		)
		(fp_rect
			(start 0.4318 0.9525)
			(end -0.4318 -0.9525)
			(stroke
				(width 0)
				(type default)
			)
			(fill no)
			(layer "B.Fab")
		)
		(pad "1" smd custom
			(at 0 -0.4445 180)
			(size 0.1524 0.1524)
			(layers "B.Cu" "B.Mask" "B.Paste")
			(net "P1V8")
			(options
				(clearance outline)
				(anchor circle)
			)
			(primitives
				(gr_poly
					(pts
						(arc
							(start 0.3048 0.2032)
							(mid 0.275042 0.275042)
							(end 0.2032 0.3048)
						)
						(arc
							(start -0.2032 0.3048)
							(mid -0.275042 0.275042)
							(end -0.3048 0.2032)
						)
						(arc
							(start -0.3048 -0.2032)
							(mid -0.275042 -0.275042)
							(end -0.2032 -0.3048)
						)
						(arc
							(start 0.2032 -0.3048)
							(mid 0.275042 -0.275042)
							(end 0.3048 -0.2032)
						)
					)
					(width 0)
					(fill yes)
				)
			)
		)
		(pad "2" smd custom
			(at 0 0.4445 180)
			(size 0.1524 0.1524)
			(layers "B.Cu" "B.Mask" "B.Paste")
			(net "GND")
			(options
				(clearance outline)
				(anchor circle)
			)
			(primitives
				(gr_poly
					(pts
						(arc
							(start 0.3048 0.2032)
							(mid 0.275042 0.275042)
							(end 0.2032 0.3048)
						)
						(arc
							(start -0.2032 0.3048)
							(mid -0.275042 0.275042)
							(end -0.3048 0.2032)
						)
						(arc
							(start -0.3048 -0.2032)
							(mid -0.275042 -0.275042)
							(end -0.2032 -0.3048)
						)
						(arc
							(start 0.2032 -0.3048)
							(mid 0.275042 -0.275042)
							(end 0.3048 -0.2032)
						)
					)
					(width 0)
					(fill yes)
				)
			)
		)
	)
	(footprint ""
		(layer "B.Cu")
		(at 208.3054 -64.1604)
		(property "Reference" "TP113"
			(at 0 0 0)
			(layer "B.SilkS")
			(hide yes)
			(effects
				(font
					(size 1.27 1.27)
				)
				(justify mirror)
			)
		)
		(property "Value" "TPAD28-2-GP"
			(at 0.0127 -1.6637 0)
			(unlocked yes)
			(layer "B.Fab")
			(hide yes)
			(effects
				(font
					(size 1.016 1.016)
					(thickness 0.1524)
				)
				(justify mirror)
			)
		)
		(property "Device Type" "TPAD28"
			(at 0.0127 -3.1877 0)
			(unlocked yes)
			(layer "B.Fab")
			(hide yes)
			(effects
				(font
					(size 1.016 1.016)
					(thickness 0.1524)
				)
				(justify mirror)
			)
		)
		(duplicate_pad_numbers_are_jumpers no)
		(fp_poly
			(pts
				(arc
					(start 0.3556 0)
					(mid -0.3556 0)
					(end 0.3556 0)
				)
			)
			(stroke
				(width 0)
				(type default)
			)
			(fill no)
			(layer "B.CrtYd")
		)
		(fp_poly
			(pts
				(arc
					(start 0.6096 0)
					(mid -0.6096 0)
					(end 0.6096 0)
				)
			)
			(stroke
				(width 0)
				(type default)
			)
			(fill no)
			(layer "B.Fab")
		)
		(pad "1" smd circle
			(at 0 0 180)
			(size 0.7112 0.7112)
			(layers "B.Cu" "B.Mask" "B.Paste")
			(net "SIO_DIN_0")
		)
	)
	(footprint ""
		(layer "B.Cu")
		(at 61.0108 -139.8016 90)
		(property "Reference" "R273"
			(at 0 0 90)
			(layer "B.SilkS")
			(hide yes)
			(effects
				(font
					(size 1.27 1.27)
				)
				(justify mirror)
			)
		)
		(property "Value" "4K7R2F-GP"
			(at -0.064008 -3.993896 90)
			(unlocked yes)
			(layer "B.Fab")
			(hide yes)
			(effects
				(font
					(size 1.016 1.016)
					(thickness 0.1524)
				)
				(justify mirror)
			)
		)
		(property "Device Type" "R402H16"
			(at -0.064008 -5.517896 90)
			(unlocked yes)
			(layer "B.Fab")
			(hide yes)
			(effects
				(font
					(size 1.016 1.016)
					(thickness 0.1524)
				)
				(justify mirror)
			)
		)
		(duplicate_pad_numbers_are_jumpers no)
		(fp_line
			(start 0.508 -0.9398)
			(end 0.508 0.9398)
			(stroke
				(width 0.1524)
				(type default)
			)
			(layer "B.SilkS")
		)
		(fp_line
			(start -0.508 -0.9398)
			(end 0.508 -0.9398)
			(stroke
				(width 0.1524)
				(type default)
			)
			(layer "B.SilkS")
		)
		(fp_rect
			(start 0.508 0.9398)
			(end -0.508 -0.9398)
			(stroke
				(width 0)
				(type default)
			)
			(fill no)
			(layer "B.CrtYd")
		)
		(fp_rect
			(start 0.508 0.9398)
			(end -0.508 -0.9398)
			(stroke
				(width 0)
				(type default)
			)
			(fill no)
			(layer "B.Fab")
		)
		(pad "1" smd custom
			(at 0 -0.4445 270)
			(size 0.1397 0.1397)
			(layers "B.Cu" "B.Mask" "B.Paste")
			(net "SYS_PWR_LED")
			(options
				(clearance outline)
				(anchor circle)
			)
			(primitives
				(gr_poly
					(pts
						(arc
							(start -0.1778 0.2794)
							(mid -0.249642 0.249642)
							(end -0.2794 0.1778)
						)
						(arc
							(start -0.2794 -0.1778)
							(mid -0.249642 -0.249642)
							(end -0.1778 -0.2794)
						)
						(arc
							(start 0.1778 -0.2794)
							(mid 0.249642 -0.249642)
							(end 0.2794 -0.1778)
						)
						(arc
							(start 0.2794 0.1778)
							(mid 0.249642 0.249642)
							(end 0.1778 0.2794)
						)
					)
					(width 0)
					(fill yes)
				)
			)
		)
		(pad "2" smd custom
			(at 0 0.4445 270)
			(size 0.1397 0.1397)
			(layers "B.Cu" "B.Mask" "B.Paste")
			(net "GND")
			(options
				(clearance outline)
				(anchor circle)
			)
			(primitives
				(gr_poly
					(pts
						(arc
							(start -0.1778 0.2794)
							(mid -0.249642 0.249642)
							(end -0.2794 0.1778)
						)
						(arc
							(start -0.2794 -0.1778)
							(mid -0.249642 -0.249642)
							(end -0.1778 -0.2794)
						)
						(arc
							(start 0.1778 -0.2794)
							(mid 0.249642 -0.249642)
							(end 0.2794 -0.1778)
						)
						(arc
							(start 0.2794 0.1778)
							(mid 0.249642 0.249642)
							(end 0.1778 0.2794)
						)
					)
					(width 0)
					(fill yes)
				)
			)
		)
	)
	(footprint ""
		(layer "B.Cu")
		(at 188.548518 -81.153 180)
		(property "Reference" "C303"
			(at 0 0 0)
			(layer "B.SilkS")
			(hide yes)
			(effects
				(font
					(size 1.27 1.27)
				)
				(justify mirror)
			)
		)
		(property "Value" "SCD22U10V1KX-GP"
			(at 2.8321 -1.7399 180)
			(unlocked yes)
			(layer "B.Fab")
			(hide yes)
			(effects
				(font
					(size 1.016 1.016)
					(thickness 0.1524)
				)
				(justify mirror)
			)
		)
		(property "Device Type" "C0201H13"
			(at 2.8321 -3.2639 180)
			(unlocked yes)
			(layer "B.Fab")
			(hide yes)
			(effects
				(font
					(size 1.016 1.016)
					(thickness 0.1524)
				)
				(justify mirror)
			)
		)
		(duplicate_pad_numbers_are_jumpers no)
		(fp_rect
			(start 0.2794 0.6477)
			(end -0.2794 -0.6477)
			(stroke
				(width 0)
				(type default)
			)
			(fill no)
			(layer "B.CrtYd")
		)
		(fp_rect
			(start 0.2794 0.6477)
			(end -0.2794 -0.6477)
			(stroke
				(width 0)
				(type default)
			)
			(fill no)
			(layer "B.Fab")
		)
		(pad "1" smd custom
			(at 0 -0.2794)
			(size 0.0762 0.0762)
			(layers "B.Cu" "B.Mask" "B.Paste")
			(net "PCIE_IOM_TO_COMP_15_DP_C")
			(options
				(clearance outline)
				(anchor circle)
			)
			(primitives
				(gr_poly
					(pts
						(arc
							(start 0.1524 0.127)
							(mid 0.137521 0.162921)
							(end 0.1016 0.1778)
						)
						(arc
							(start -0.1016 0.1778)
							(mid -0.137521 0.162921)
							(end -0.1524 0.127)
						)
						(arc
							(start -0.1524 -0.127)
							(mid -0.137521 -0.162921)
							(end -0.1016 -0.1778)
						)
						(arc
							(start 0.1016 -0.1778)
							(mid 0.137521 -0.162921)
							(end 0.1524 -0.127)
						)
					)
					(width 0)
					(fill yes)
				)
			)
		)
		(pad "2" smd custom
			(at 0 0.2794)
			(size 0.0762 0.0762)
			(layers "B.Cu" "B.Mask" "B.Paste")
			(net "PCIE_IOM_TO_COMP_15_DP")
			(options
				(clearance outline)
				(anchor circle)
			)
			(primitives
				(gr_poly
					(pts
						(arc
							(start 0.1524 0.127)
							(mid 0.137521 0.162921)
							(end 0.1016 0.1778)
						)
						(arc
							(start -0.1016 0.1778)
							(mid -0.137521 0.162921)
							(end -0.1524 0.127)
						)
						(arc
							(start -0.1524 -0.127)
							(mid -0.137521 -0.162921)
							(end -0.1016 -0.1778)
						)
						(arc
							(start 0.1016 -0.1778)
							(mid 0.137521 -0.162921)
							(end 0.1524 -0.127)
						)
					)
					(width 0)
					(fill yes)
				)
			)
		)
	)
	(footprint ""
		(layer "B.Cu")
		(at 62.75578 -158.22676 180)
		(property "Reference" "C81"
			(at 0 0 0)
			(layer "B.SilkS")
			(hide yes)
			(effects
				(font
					(size 1.27 1.27)
				)
				(justify mirror)
			)
		)
		(property "Value" "SC4D7U25V5KX-1-GP"
			(at 0.0762 -6.1214 180)
			(unlocked yes)
			(layer "B.Fab")
			(hide yes)
			(effects
				(font
					(size 1.016 1.016)
					(thickness 0.1524)
				)
				(justify mirror)
			)
		)
		(property "Device Type" "C805H58"
			(at 0.0762 -8.1534 180)
			(unlocked yes)
			(layer "B.Fab")
			(hide yes)
			(effects
				(font
					(size 1.016 1.016)
					(thickness 0.1524)
				)
				(justify mirror)
			)
		)
		(duplicate_pad_numbers_are_jumpers no)
		(fp_line
			(start -0.635 0)
			(end 0.635 0)
			(stroke
				(width 0.508)
				(type default)
			)
			(layer "B.SilkS")
		)
		(fp_rect
			(start 0.9652 1.778)
			(end -0.9652 -1.778)
			(stroke
				(width 0)
				(type default)
			)
			(fill no)
			(layer "B.CrtYd")
		)
		(fp_poly
			(pts
				(xy 0.9652 -1.778) (xy -0.9652 -1.778) (xy -0.9652 1.778) (xy 0.9652 1.778)
			)
			(stroke
				(width 0)
				(type default)
			)
			(fill no)
			(layer "B.Fab")
		)
		(pad "1" smd rect
			(at 0 -0.9652)
			(size 1.397 1.143)
			(layers "B.Cu" "B.Mask" "B.Paste")
			(net "P3V3_STBY")
		)
		(pad "2" smd rect
			(at 0 0.9652)
			(size 1.397 1.143)
			(layers "B.Cu" "B.Mask" "B.Paste")
			(net "GND")
		)
	)
	(footprint ""
		(layer "B.Cu")
		(at 57.365392 -147.743164 90)
		(property "Reference" "R365"
			(at 0 0 90)
			(layer "B.SilkS")
			(hide yes)
			(effects
				(font
					(size 1.27 1.27)
				)
				(justify mirror)
			)
		)
		(property "Value" "4K7R2F-GP"
			(at -0.064008 -3.993896 90)
			(unlocked yes)
			(layer "B.Fab")
			(hide yes)
			(effects
				(font
					(size 1.016 1.016)
					(thickness 0.1524)
				)
				(justify mirror)
			)
		)
		(property "Device Type" "R402H16"
			(at -0.064008 -5.517896 90)
			(unlocked yes)
			(layer "B.Fab")
			(hide yes)
			(effects
				(font
					(size 1.016 1.016)
					(thickness 0.1524)
				)
				(justify mirror)
			)
		)
		(duplicate_pad_numbers_are_jumpers no)
		(fp_line
			(start 0.508 -0.9398)
			(end 0.508 0.9398)
			(stroke
				(width 0.1524)
				(type default)
			)
			(layer "B.SilkS")
		)
		(fp_line
			(start -0.508 -0.9398)
			(end 0.508 -0.9398)
			(stroke
				(width 0.1524)
				(type default)
			)
			(layer "B.SilkS")
		)
		(fp_rect
			(start 0.508 0.9398)
			(end -0.508 -0.9398)
			(stroke
				(width 0)
				(type default)
			)
			(fill no)
			(layer "B.CrtYd")
		)
		(fp_rect
			(start 0.508 0.9398)
			(end -0.508 -0.9398)
			(stroke
				(width 0)
				(type default)
			)
			(fill no)
			(layer "B.Fab")
		)
		(pad "1" smd custom
			(at 0 -0.4445 270)
			(size 0.1397 0.1397)
			(layers "B.Cu" "B.Mask" "B.Paste")
			(net "BMC0_JTAG_RTCK")
			(options
				(clearance outline)
				(anchor circle)
			)
			(primitives
				(gr_poly
					(pts
						(arc
							(start -0.1778 0.2794)
							(mid -0.249642 0.249642)
							(end -0.2794 0.1778)
						)
						(arc
							(start -0.2794 -0.1778)
							(mid -0.249642 -0.249642)
							(end -0.1778 -0.2794)
						)
						(arc
							(start 0.1778 -0.2794)
							(mid 0.249642 -0.249642)
							(end 0.2794 -0.1778)
						)
						(arc
							(start 0.2794 0.1778)
							(mid 0.249642 0.249642)
							(end 0.1778 0.2794)
						)
					)
					(width 0)
					(fill yes)
				)
			)
		)
		(pad "2" smd custom
			(at 0 0.4445 270)
			(size 0.1397 0.1397)
			(layers "B.Cu" "B.Mask" "B.Paste")
			(net "GND")
			(options
				(clearance outline)
				(anchor circle)
			)
			(primitives
				(gr_poly
					(pts
						(arc
							(start -0.1778 0.2794)
							(mid -0.249642 0.249642)
							(end -0.2794 0.1778)
						)
						(arc
							(start -0.2794 -0.1778)
							(mid -0.249642 -0.249642)
							(end -0.1778 -0.2794)
						)
						(arc
							(start 0.1778 -0.2794)
							(mid 0.249642 -0.249642)
							(end 0.2794 -0.1778)
						)
						(arc
							(start 0.2794 0.1778)
							(mid 0.249642 0.249642)
							(end 0.1778 0.2794)
						)
					)
					(width 0)
					(fill yes)
				)
			)
		)
	)
	(footprint ""
		(layer "B.Cu")
		(at 180.2511 -63.3476)
		(property "Reference" "TP123"
			(at 0 0 0)
			(layer "B.SilkS")
			(hide yes)
			(effects
				(font
					(size 1.27 1.27)
				)
				(justify mirror)
			)
		)
		(property "Value" "TPAD28-2-GP"
			(at 0.0127 -1.6637 0)
			(unlocked yes)
			(layer "B.Fab")
			(hide yes)
			(effects
				(font
					(size 1.016 1.016)
					(thickness 0.1524)
				)
				(justify mirror)
			)
		)
		(property "Device Type" "TPAD28"
			(at 0.0127 -3.1877 0)
			(unlocked yes)
			(layer "B.Fab")
			(hide yes)
			(effects
				(font
					(size 1.016 1.016)
					(thickness 0.1524)
				)
				(justify mirror)
			)
		)
		(duplicate_pad_numbers_are_jumpers no)
		(fp_poly
			(pts
				(arc
					(start 0.3556 0)
					(mid -0.3556 0)
					(end 0.3556 0)
				)
			)
			(stroke
				(width 0)
				(type default)
			)
			(fill no)
			(layer "B.CrtYd")
		)
		(fp_poly
			(pts
				(arc
					(start 0.6096 0)
					(mid -0.6096 0)
					(end 0.6096 0)
				)
			)
			(stroke
				(width 0)
				(type default)
			)
			(fill no)
			(layer "B.Fab")
		)
		(pad "1" smd circle
			(at 0 0 180)
			(size 0.7112 0.7112)
			(layers "B.Cu" "B.Mask" "B.Paste")
			(net "IOC_GPIO_32")
		)
	)
	(footprint ""
		(layer "B.Cu")
		(at 19.870674 -143.306546 180)
		(property "Reference" "C66"
			(at 0 0 0)
			(layer "B.SilkS")
			(hide yes)
			(effects
				(font
					(size 1.27 1.27)
				)
				(justify mirror)
			)
		)
		(property "Value" "SCD1U16V2KX-3GP"
			(at -1.1811 -2.7051 180)
			(unlocked yes)
			(layer "B.Fab")
			(hide yes)
			(effects
				(font
					(size 1.016 1.016)
					(thickness 0.1524)
				)
				(justify mirror)
			)
		)
		(property "Device Type" "C402H22"
			(at -1.1811 -4.2291 180)
			(unlocked yes)
			(layer "B.Fab")
			(hide yes)
			(effects
				(font
					(size 1.016 1.016)
					(thickness 0.1524)
				)
				(justify mirror)
			)
		)
		(duplicate_pad_numbers_are_jumpers no)
		(fp_rect
			(start 0.4318 0.9525)
			(end -0.4318 -0.9525)
			(stroke
				(width 0)
				(type default)
			)
			(fill no)
			(layer "B.CrtYd")
		)
		(fp_rect
			(start 0.4318 0.9525)
			(end -0.4318 -0.9525)
			(stroke
				(width 0)
				(type default)
			)
			(fill no)
			(layer "B.Fab")
		)
		(pad "1" smd custom
			(at 0 -0.4445)
			(size 0.1524 0.1524)
			(layers "B.Cu" "B.Mask" "B.Paste")
			(net "MEMCK_TER")
			(options
				(clearance outline)
				(anchor circle)
			)
			(primitives
				(gr_poly
					(pts
						(arc
							(start 0.3048 0.2032)
							(mid 0.275042 0.275042)
							(end 0.2032 0.3048)
						)
						(arc
							(start -0.2032 0.3048)
							(mid -0.275042 0.275042)
							(end -0.3048 0.2032)
						)
						(arc
							(start -0.3048 -0.2032)
							(mid -0.275042 -0.275042)
							(end -0.2032 -0.3048)
						)
						(arc
							(start 0.2032 -0.3048)
							(mid 0.275042 -0.275042)
							(end 0.3048 -0.2032)
						)
					)
					(width 0)
					(fill yes)
				)
			)
		)
		(pad "2" smd custom
			(at 0 0.4445)
			(size 0.1524 0.1524)
			(layers "B.Cu" "B.Mask" "B.Paste")
			(net "GND")
			(options
				(clearance outline)
				(anchor circle)
			)
			(primitives
				(gr_poly
					(pts
						(arc
							(start 0.3048 0.2032)
							(mid 0.275042 0.275042)
							(end 0.2032 0.3048)
						)
						(arc
							(start -0.2032 0.3048)
							(mid -0.275042 0.275042)
							(end -0.3048 0.2032)
						)
						(arc
							(start -0.3048 -0.2032)
							(mid -0.275042 -0.275042)
							(end -0.2032 -0.3048)
						)
						(arc
							(start 0.2032 -0.3048)
							(mid 0.275042 -0.275042)
							(end 0.3048 -0.2032)
						)
					)
					(width 0)
					(fill yes)
				)
			)
		)
	)
	(footprint ""
		(layer "B.Cu")
		(at 20.376896 -141.833092 -90)
		(property "Reference" "R205"
			(at 0 0 90)
			(layer "B.SilkS")
			(hide yes)
			(effects
				(font
					(size 1.27 1.27)
				)
				(justify mirror)
			)
		)
		(property "Value" "60D4R2F-GP"
			(at -0.064008 -3.993896 270)
			(unlocked yes)
			(layer "B.Fab")
			(hide yes)
			(effects
				(font
					(size 1.016 1.016)
					(thickness 0.1524)
				)
				(justify mirror)
			)
		)
		(property "Device Type" "R402H16"
			(at -0.064008 -5.517896 270)
			(unlocked yes)
			(layer "B.Fab")
			(hide yes)
			(effects
				(font
					(size 1.016 1.016)
					(thickness 0.1524)
				)
				(justify mirror)
			)
		)
		(duplicate_pad_numbers_are_jumpers no)
		(fp_line
			(start -0.508 -0.9398)
			(end 0.508 -0.9398)
			(stroke
				(width 0.1524)
				(type default)
			)
			(layer "B.SilkS")
		)
		(fp_line
			(start 0.508 -0.9398)
			(end 0.508 0.9398)
			(stroke
				(width 0.1524)
				(type default)
			)
			(layer "B.SilkS")
		)
		(fp_rect
			(start 0.508 0.9398)
			(end -0.508 -0.9398)
			(stroke
				(width 0)
				(type default)
			)
			(fill no)
			(layer "B.CrtYd")
		)
		(fp_rect
			(start 0.508 0.9398)
			(end -0.508 -0.9398)
			(stroke
				(width 0)
				(type default)
			)
			(fill no)
			(layer "B.Fab")
		)
		(pad "1" smd custom
			(at 0 -0.4445 90)
			(size 0.1397 0.1397)
			(layers "B.Cu" "B.Mask" "B.Paste")
			(net "MEMCK_P")
			(options
				(clearance outline)
				(anchor circle)
			)
			(primitives
				(gr_poly
					(pts
						(arc
							(start -0.1778 0.2794)
							(mid -0.249642 0.249642)
							(end -0.2794 0.1778)
						)
						(arc
							(start -0.2794 -0.1778)
							(mid -0.249642 -0.249642)
							(end -0.1778 -0.2794)
						)
						(arc
							(start 0.1778 -0.2794)
							(mid 0.249642 -0.249642)
							(end 0.2794 -0.1778)
						)
						(arc
							(start 0.2794 0.1778)
							(mid 0.249642 0.249642)
							(end 0.1778 0.2794)
						)
					)
					(width 0)
					(fill yes)
				)
			)
		)
		(pad "2" smd custom
			(at 0 0.4445 90)
			(size 0.1397 0.1397)
			(layers "B.Cu" "B.Mask" "B.Paste")
			(net "MEMCK_TER")
			(options
				(clearance outline)
				(anchor circle)
			)
			(primitives
				(gr_poly
					(pts
						(arc
							(start -0.1778 0.2794)
							(mid -0.249642 0.249642)
							(end -0.2794 0.1778)
						)
						(arc
							(start -0.2794 -0.1778)
							(mid -0.249642 -0.249642)
							(end -0.1778 -0.2794)
						)
						(arc
							(start 0.1778 -0.2794)
							(mid 0.249642 -0.249642)
							(end 0.2794 -0.1778)
						)
						(arc
							(start 0.2794 0.1778)
							(mid 0.249642 0.249642)
							(end 0.1778 0.2794)
						)
					)
					(width 0)
					(fill yes)
				)
			)
		)
	)
)
